# SCM (Grand Teton) — schematic netlist excerpt (pin names and nets, part order shuffled) for the footprints in the layout excerpt that follows; sources: Cadence DE-HDL packaged netlist, KiCad conversion of 12092022_DA0F0TMDCD0_F0T_Management_Board_D_brd_V3_OCP.brd

R324  Q_RES  1K 1% CHIP  pkg 0402LF  page 20 : A = P1V2_AUX ; B = P0V6_DDR_VREF_AUX
R53  Q_RES  1K 1% EMPTY  pkg 0402LF  page 26 : A = TMC75_A1 ; B = GND

(kicad_pcb
	(version 20260206)
	(generator "pcbnew")
	(generator_version "10.0")
	(general
		(thickness 1.6)
		(legacy_teardrops no)
	)
	(paper "A4")
	(title_block
		(title "12092022_DA0F0TMDCD0_F0T_Management_Board_D_brd_V3_OCP.brd")
		(comment 1 "Grand Teton / footprints 799-800 of 1440")
	)
	(layers
		(0 "F.Cu" signal "TOP")
		(4 "In1.Cu" signal "GND")
		(6 "In2.Cu" signal "IN1")
		(8 "In3.Cu" signal "GND1")
		(10 "In4.Cu" signal "IN2")
		(12 "In5.Cu" signal "VCC")
		(14 "In6.Cu" signal "VCC1")
		(16 "In7.Cu" signal "IN3")
		(18 "In8.Cu" signal "GND2")
		(20 "In9.Cu" signal "IN4")
		(22 "In10.Cu" signal "GND3")
		(2 "B.Cu" signal "BOTTOM")
		(9 "F.Adhes" user "F.Adhesive")
		(11 "B.Adhes" user "B.Adhesive")
		(13 "F.Paste" user "Package Geometry/Pastemask Top")
		(15 "B.Paste" user "Package Geometry/Pastemask Bottom")
		(5 "F.SilkS" user "Ref Des/Silkscreen Top")
		(7 "B.SilkS" user "Ref Des/Silkscreen Bottom")
		(1 "F.Mask" user "Board Geometry/Soldermask Top")
		(3 "B.Mask" user "Board Geometry/Soldermask Bottom")
		(17 "Dwgs.User" user "User.Drawings")
		(19 "Cmts.User" user "User.Comments")
		(21 "Eco1.User" user "User.Eco1")
		(23 "Eco2.User" user "User.Eco2")
		(25 "Edge.Cuts" user "Board Geometry/Outline")
		(27 "Margin" user)
		(31 "F.CrtYd" user "Package Geometry/Place Bound Top")
		(29 "B.CrtYd" user "Package Geometry/Place Bound Bottom")
		(35 "F.Fab" user "Ref Des/Assembly Top")
		(33 "B.Fab" user "Ref Des/Assembly Bottom")
	)
	(footprint ""
		(layer "B.Cu")
		(at 82.108294 -51.730656 180)
		(property "Reference" "R324"
			(at 0 0 0)
			(layer "B.SilkS")
			(hide yes)
			(effects
				(font
					(size 1.27 1.27)
				)
				(justify mirror)
			)
		)
		(property "Value" ""
			(at 0 0 0)
			(layer "B.Fab")
			(effects
				(font
					(size 1.27 1.27)
				)
				(justify mirror)
			)
		)
		(duplicate_pad_numbers_are_jumpers no)
		(fp_line
			(start 0.7874 0.4064)
			(end 0.7874 -0.4064)
			(stroke
				(width 0.1524)
				(type default)
			)
			(layer "B.SilkS")
		)
		(fp_line
			(start 0.7874 -0.4064)
			(end -0.7874 -0.4064)
			(stroke
				(width 0.1524)
				(type default)
			)
			(layer "B.SilkS")
		)
		(fp_line
			(start -0.7874 0.4064)
			(end 0.7874 0.4064)
			(stroke
				(width 0.1524)
				(type default)
			)
			(layer "B.SilkS")
		)
		(fp_line
			(start -0.7874 -0.4064)
			(end -0.7874 0.4064)
			(stroke
				(width 0.1524)
				(type default)
			)
			(layer "B.SilkS")
		)
		(fp_line
			(start 0.67945 0.3048)
			(end 0.67945 -0.305054)
			(stroke
				(width 0.1)
				(type default)
			)
			(layer "B.Fab")
		)
		(fp_line
			(start 0.67945 -0.305054)
			(end 0.12065 -0.305054)
			(stroke
				(width 0.1)
				(type default)
			)
			(layer "B.Fab")
		)
		(fp_line
			(start 0.12065 0.3048)
			(end 0.67945 0.3048)
			(stroke
				(width 0.1)
				(type default)
			)
			(layer "B.Fab")
		)
		(fp_line
			(start 0.12065 0.2794)
			(end 0.12065 0.3048)
			(stroke
				(width 0.1)
				(type default)
			)
			(layer "B.Fab")
		)
		(fp_line
			(start 0.12065 -0.2794)
			(end -0.12065 -0.2794)
			(stroke
				(width 0.1)
				(type default)
			)
			(layer "B.Fab")
		)
		(fp_line
			(start 0.12065 -0.305054)
			(end 0.12065 -0.2794)
			(stroke
				(width 0.1)
				(type default)
			)
			(layer "B.Fab")
		)
		(fp_line
			(start -0.120396 0.3048)
			(end -0.120396 0.2794)
			(stroke
				(width 0.1)
				(type default)
			)
			(layer "B.Fab")
		)
		(fp_line
			(start -0.120396 0.2794)
			(end 0.12065 0.2794)
			(stroke
				(width 0.1)
				(type default)
			)
			(layer "B.Fab")
		)
		(fp_line
			(start -0.12065 -0.2794)
			(end -0.12065 -0.3048)
			(stroke
				(width 0.1)
				(type default)
			)
			(layer "B.Fab")
		)
		(fp_line
			(start -0.12065 -0.3048)
			(end -0.67945 -0.3048)
			(stroke
				(width 0.1)
				(type default)
			)
			(layer "B.Fab")
		)
		(fp_line
			(start -0.67945 0.3048)
			(end -0.120396 0.3048)
			(stroke
				(width 0.1)
				(type default)
			)
			(layer "B.Fab")
		)
		(fp_line
			(start -0.67945 -0.3048)
			(end -0.67945 0.3048)
			(stroke
				(width 0.1)
				(type default)
			)
			(layer "B.Fab")
		)
		(pad "1" smd circle
			(at 0.40005 0)
			(size 0 0)
			(layers "B.Cu" "B.Mask" "B.Paste")
			(net "P1V2_AUX")
		)
		(pad "2" smd circle
			(at -0.40005 0)
			(size 0 0)
			(layers "B.Cu" "B.Mask" "B.Paste")
			(net "P0V6_DDR_VREF_AUX")
		)
	)
	(footprint ""
		(layer "B.Cu")
		(at 19.431 -17.907 90)
		(property "Reference" "R53"
			(at 0 0 90)
			(layer "B.SilkS")
			(hide yes)
			(effects
				(font
					(size 1.27 1.27)
				)
				(justify mirror)
			)
		)
		(property "Value" ""
			(at 0 0 90)
			(layer "B.Fab")
			(effects
				(font
					(size 1.27 1.27)
				)
				(justify mirror)
			)
		)
		(duplicate_pad_numbers_are_jumpers no)
		(fp_line
			(start 0.7874 -0.4064)
			(end -0.7874 -0.4064)
			(stroke
				(width 0.1524)
				(type default)
			)
			(layer "B.SilkS")
		)
		(fp_line
			(start -0.7874 -0.4064)
			(end -0.7874 0.4064)
			(stroke
				(width 0.1524)
				(type default)
			)
			(layer "B.SilkS")
		)
		(fp_line
			(start 0.7874 0.4064)
			(end 0.7874 -0.4064)
			(stroke
				(width 0.1524)
				(type default)
			)
			(layer "B.SilkS")
		)
		(fp_line
			(start -0.7874 0.4064)
			(end 0.7874 0.4064)
			(stroke
				(width 0.1524)
				(type default)
			)
			(layer "B.SilkS")
		)
		(fp_line
			(start 0.67945 -0.305054)
			(end 0.12065 -0.305054)
			(stroke
				(width 0.1)
				(type default)
			)
			(layer "B.Fab")
		)
		(fp_line
			(start 0.12065 -0.305054)
			(end 0.12065 -0.2794)
			(stroke
				(width 0.1)
				(type default)
			)
			(layer "B.Fab")
		)
		(fp_line
			(start -0.12065 -0.3048)
			(end -0.67945 -0.3048)
			(stroke
				(width 0.1)
				(type default)
			)
			(layer "B.Fab")
		)
		(fp_line
			(start -0.67945 -0.3048)
			(end -0.67945 0.3048)
			(stroke
				(width 0.1)
				(type default)
			)
			(layer "B.Fab")
		)
		(fp_line
			(start 0.12065 -0.2794)
			(end -0.12065 -0.2794)
			(stroke
				(width 0.1)
				(type default)
			)
			(layer "B.Fab")
		)
		(fp_line
			(start -0.12065 -0.2794)
			(end -0.12065 -0.3048)
			(stroke
				(width 0.1)
				(type default)
			)
			(layer "B.Fab")
		)
		(fp_line
			(start 0.12065 0.2794)
			(end 0.12065 0.3048)
			(stroke
				(width 0.1)
				(type default)
			)
			(layer "B.Fab")
		)
		(fp_line
			(start -0.120396 0.2794)
			(end 0.12065 0.2794)
			(stroke
				(width 0.1)
				(type default)
			)
			(layer "B.Fab")
		)
		(fp_line
			(start 0.67945 0.3048)
			(end 0.67945 -0.305054)
			(stroke
				(width 0.1)
				(type default)
			)
			(layer "B.Fab")
		)
		(fp_line
			(start 0.12065 0.3048)
			(end 0.67945 0.3048)
			(stroke
				(width 0.1)
				(type default)
			)
			(layer "B.Fab")
		)
		(fp_line
			(start -0.120396 0.3048)
			(end -0.120396 0.2794)
			(stroke
				(width 0.1)
				(type default)
			)
			(layer "B.Fab")
		)
		(fp_line
			(start -0.67945 0.3048)
			(end -0.120396 0.3048)
			(stroke
				(width 0.1)
				(type default)
			)
			(layer "B.Fab")
		)
		(pad "1" smd circle
			(at 0.40005 0 270)
			(size 0 0)
			(layers "B.Cu" "B.Mask" "B.Paste")
			(net "TMC75_A1")
		)
		(pad "2" smd circle
			(at -0.40005 0 270)
			(size 0 0)
			(layers "B.Cu" "B.Mask" "B.Paste")
			(net "GND")
		)
	)
)
